G04 ================== begin FILE IDENTIFICATION RECORD ==================*
G04 Layout Name:  t6mg_pdb_a_v02_0109_1330.brd*
G04 Film Name:    pmb*
G04 File Format:  Gerber RS274X*
G04 File Origin:  Cadence Allegro 16.3-S038*
G04 Origin Date:  Mon Jan 13 14:11:54 2014*
G04 *
G04 Layer:  VIA CLASS/PASTEMASK_BOTTOM*
G04 Layer:  PIN/PASTEMASK_BOTTOM*
G04 Layer:  PACKAGE GEOMETRY/PASTEMASK_BOTTOM*
G04 Layer:  MANUFACTURING/PHOTOPLOT_OUTLINE*
G04 Layer:  DRAWING FORMAT/TITLE_BLOCK*
G04 Layer:  DRAWING FORMAT/TITLE_DATA_PMB*
G04 *
G04 Offset:    (0.00 0.00)*
G04 Mirror:    No*
G04 Mode:      Positive*
G04 Rotation:  0*
G04 FullContactRelief:  No*
G04 UndefLineWidth:     6.00*
G04 ================== end FILE IDENTIFICATION RECORD ====================*
%FSLAX25Y25*MOIN*%
%IR0*IPPOS*OFA0.00000B0.00000*MIA0B0*SFA1.00000B1.00000*%
%ADD19C,.03*%
%ADD12C,.052*%
%ADD15C,.026*%
%ADD10C,.063*%
%ADD22C,.064*%
%ADD17C,.055*%
%ADD21C,.039*%
%ADD14C,.093*%
%ADD20R,.052X.052*%
%ADD13C,.077*%
%ADD11R,.063X.063*%
%ADD23R,.064X.064*%
%ADD18R,.055X.055*%
%ADD16R,.077X.077*%
%ADD25R,.02X.018*%
%ADD26R,.018X.02*%
%ADD24R,.014X.059*%
%ADD27C,.006*%
G75*
%LPD*%
G75*
G54D10*
X22756Y113818D03*
X22480Y316838D03*
Y328649D03*
X22756Y1866819D03*
Y1948818D03*
Y2023818D03*
G54D11*
Y125629D03*
X22480Y340460D03*
X22756Y1878630D03*
Y1960629D03*
Y2035629D03*
G54D20*
X55254Y554500D03*
Y1612504D03*
G54D21*
X55158Y882277D03*
X344826Y2035270D03*
X389572Y66182D03*
G54D12*
X14073Y512197D03*
Y522000D03*
Y552000D03*
Y561803D03*
Y1580004D03*
Y1570201D03*
Y1610004D03*
Y1619807D03*
X65254Y519500D03*
Y529500D03*
Y539500D03*
X55254Y524500D03*
Y534500D03*
X65254Y549500D03*
X55254Y544500D03*
X65254Y1577504D03*
Y1587504D03*
Y1597504D03*
X55254Y1582504D03*
Y1592504D03*
Y1602504D03*
X65254Y1607504D03*
G54D13*
X23402Y1668874D03*
Y1685410D03*
Y1701945D03*
Y1718480D03*
Y1735016D03*
Y1751551D03*
Y1768087D03*
Y1784622D03*
Y1817693D03*
Y1801158D03*
X45056Y1668874D03*
Y1685410D03*
Y1701945D03*
Y1718480D03*
Y1735016D03*
Y1751551D03*
Y1768087D03*
Y1784622D03*
Y1801158D03*
G54D22*
X119920Y18071D03*
Y28071D03*
Y38071D03*
Y48071D03*
Y58071D03*
Y68071D03*
Y78071D03*
Y88071D03*
Y98071D03*
Y108071D03*
Y118071D03*
Y128071D03*
Y138071D03*
Y148071D03*
Y158071D03*
Y168071D03*
Y178071D03*
Y188071D03*
Y198071D03*
Y208071D03*
Y218071D03*
Y228071D03*
Y238071D03*
Y248071D03*
Y258071D03*
Y268071D03*
Y278071D03*
Y288071D03*
Y298071D03*
Y308071D03*
Y318071D03*
Y366102D03*
Y376102D03*
Y386102D03*
Y396102D03*
Y406102D03*
Y416102D03*
Y426102D03*
Y436102D03*
Y446102D03*
Y456102D03*
Y466102D03*
Y476102D03*
Y486102D03*
Y496102D03*
Y506102D03*
Y516102D03*
Y526102D03*
Y536102D03*
Y546102D03*
Y556102D03*
Y566102D03*
Y576102D03*
Y586102D03*
Y596102D03*
Y606102D03*
Y616102D03*
Y626102D03*
Y636102D03*
Y646102D03*
Y656102D03*
Y666102D03*
Y714134D03*
Y724134D03*
Y734134D03*
Y744134D03*
Y754134D03*
Y764134D03*
Y774134D03*
Y784134D03*
Y794134D03*
Y804134D03*
Y814134D03*
Y824134D03*
Y834134D03*
Y844134D03*
Y854134D03*
Y864134D03*
Y874134D03*
Y884134D03*
Y894134D03*
Y904134D03*
Y914134D03*
Y924134D03*
Y934134D03*
Y944134D03*
Y954134D03*
Y964134D03*
Y974134D03*
Y984134D03*
Y994134D03*
Y1004134D03*
Y1014134D03*
Y1062165D03*
Y1072165D03*
Y1082165D03*
Y1092165D03*
Y1102165D03*
Y1112165D03*
Y1122165D03*
Y1132165D03*
Y1142165D03*
Y1152165D03*
Y1162165D03*
Y1172165D03*
Y1182165D03*
Y1192165D03*
Y1202165D03*
Y1212165D03*
Y1222165D03*
Y1232165D03*
Y1242165D03*
Y1252165D03*
Y1262165D03*
Y1272165D03*
Y1282165D03*
Y1292165D03*
Y1302165D03*
Y1312165D03*
Y1322165D03*
Y1332165D03*
Y1342165D03*
Y1352165D03*
Y1362165D03*
Y1410197D03*
Y1420197D03*
Y1430197D03*
Y1440197D03*
Y1450197D03*
Y1460197D03*
Y1470197D03*
Y1480197D03*
Y1490197D03*
Y1500197D03*
Y1510197D03*
Y1520197D03*
Y1530197D03*
Y1540197D03*
Y1550197D03*
Y1560197D03*
Y1570197D03*
Y1580197D03*
Y1590197D03*
Y1600197D03*
Y1610197D03*
Y1620197D03*
Y1630197D03*
Y1640197D03*
Y1650197D03*
Y1660197D03*
Y1670197D03*
Y1680197D03*
Y1690197D03*
Y1700197D03*
Y1710197D03*
Y1758228D03*
Y1768228D03*
Y1778228D03*
Y1788228D03*
Y1798228D03*
Y1808228D03*
Y1818228D03*
Y1828228D03*
Y1838228D03*
Y1848228D03*
Y1858228D03*
Y1868228D03*
Y1878228D03*
Y1888228D03*
Y1898228D03*
Y1908228D03*
Y1918228D03*
Y1928228D03*
Y1938228D03*
Y1948228D03*
Y1958228D03*
Y1968228D03*
Y1978228D03*
Y1988228D03*
Y1998228D03*
Y2008228D03*
Y2018228D03*
Y2028228D03*
Y2038228D03*
Y2048228D03*
Y2058228D03*
X139920Y28071D03*
Y18071D03*
Y58071D03*
Y48071D03*
Y38071D03*
Y78071D03*
Y68071D03*
Y98071D03*
Y88071D03*
Y128071D03*
Y118071D03*
Y108071D03*
Y148071D03*
Y138071D03*
Y178071D03*
Y168071D03*
Y158071D03*
Y198071D03*
Y188071D03*
Y228071D03*
Y218071D03*
Y208071D03*
Y248071D03*
Y238071D03*
Y268071D03*
Y258071D03*
Y298071D03*
Y288071D03*
Y278071D03*
Y318071D03*
Y308071D03*
Y328071D03*
Y366102D03*
Y396102D03*
Y386102D03*
Y376102D03*
Y416102D03*
Y406102D03*
Y436102D03*
Y426102D03*
Y466102D03*
Y456102D03*
Y446102D03*
Y486102D03*
Y476102D03*
Y516102D03*
Y506102D03*
Y496102D03*
Y536102D03*
Y526102D03*
Y566102D03*
Y556102D03*
Y546102D03*
Y586102D03*
Y576102D03*
Y606102D03*
Y596102D03*
Y636102D03*
Y626102D03*
Y616102D03*
Y656102D03*
Y646102D03*
Y676102D03*
Y666102D03*
Y734134D03*
Y724134D03*
Y714134D03*
Y754134D03*
Y744134D03*
Y774134D03*
Y764134D03*
Y804134D03*
Y794134D03*
Y784134D03*
Y824134D03*
Y814134D03*
Y854134D03*
Y844134D03*
Y834134D03*
Y874134D03*
Y864134D03*
Y904134D03*
Y894134D03*
Y884134D03*
Y924134D03*
Y914134D03*
Y944134D03*
Y934134D03*
Y974134D03*
Y964134D03*
Y954134D03*
Y994134D03*
Y984134D03*
Y1024134D03*
Y1014134D03*
Y1004134D03*
Y1072165D03*
Y1062165D03*
Y1092165D03*
Y1082165D03*
Y1122165D03*
Y1112165D03*
Y1102165D03*
Y1142165D03*
Y1132165D03*
Y1162165D03*
Y1152165D03*
Y1192165D03*
Y1182165D03*
Y1172165D03*
Y1212165D03*
Y1202165D03*
Y1242165D03*
Y1232165D03*
Y1222165D03*
Y1262165D03*
Y1252165D03*
Y1282165D03*
Y1272165D03*
Y1312165D03*
Y1302165D03*
Y1292165D03*
Y1332165D03*
Y1322165D03*
Y1362165D03*
Y1352165D03*
Y1342165D03*
Y1372165D03*
Y1410197D03*
Y1430197D03*
Y1420197D03*
Y1460197D03*
Y1450197D03*
Y1440197D03*
Y1480197D03*
Y1470197D03*
Y1500197D03*
Y1490197D03*
Y1530197D03*
Y1520197D03*
Y1510197D03*
Y1550197D03*
Y1540197D03*
Y1580197D03*
Y1570197D03*
Y1560197D03*
Y1600197D03*
Y1590197D03*
Y1620197D03*
Y1610197D03*
Y1650197D03*
Y1640197D03*
Y1630197D03*
Y1670197D03*
Y1660197D03*
Y1700197D03*
Y1690197D03*
Y1680197D03*
Y1720197D03*
Y1710197D03*
Y1768228D03*
Y1758228D03*
Y1798228D03*
Y1788228D03*
Y1778228D03*
Y1818228D03*
Y1808228D03*
Y1838228D03*
Y1828228D03*
Y1868228D03*
Y1858228D03*
Y1848228D03*
Y1888228D03*
Y1878228D03*
Y1918228D03*
Y1908228D03*
Y1898228D03*
Y1938228D03*
Y1928228D03*
Y1958228D03*
Y1948228D03*
Y1988228D03*
Y1978228D03*
Y1968228D03*
Y2008228D03*
Y1998228D03*
Y2038228D03*
Y2028228D03*
Y2018228D03*
Y2058228D03*
Y2048228D03*
Y2068228D03*
G54D23*
X119920Y328071D03*
Y676102D03*
Y1024134D03*
Y1372165D03*
Y1720197D03*
Y2068228D03*
G54D14*
X45411Y505996D03*
Y568004D03*
Y1564000D03*
Y1626008D03*
G54D24*
X359677Y306891D03*
X362236D03*
Y329891D03*
X359677D03*
X354000Y656986D03*
X356559D03*
X359118D03*
X361677D03*
Y679986D03*
X359118D03*
X356559D03*
X354000D03*
X351983Y1882006D03*
X354542D03*
X357101D03*
X359660D03*
X362219D03*
Y1905006D03*
X359660D03*
X357101D03*
X354542D03*
X351983D03*
X364795Y306891D03*
X367354D03*
X369913D03*
X372472D03*
X375031D03*
Y329891D03*
X372472D03*
X369913D03*
X367354D03*
X364795D03*
X364236Y656986D03*
X366795D03*
X369354D03*
Y679986D03*
X366795D03*
X364236D03*
X372122Y1347255D03*
X374681D03*
X377240D03*
X379799D03*
X382358D03*
X384917D03*
X387476D03*
Y1370255D03*
X384917D03*
X382358D03*
X379799D03*
X377240D03*
X374681D03*
X372122D03*
X364778Y1882006D03*
X367337D03*
Y1905006D03*
X364778D03*
G54D15*
X49441Y1238962D03*
X45581Y1278420D03*
X45413Y1283724D03*
X45244Y1289067D03*
X45350Y1299697D03*
X45267Y1294203D03*
X45281Y1310893D03*
X45244Y1305787D03*
X46980Y1325843D03*
Y1315843D03*
Y1320843D03*
Y1330843D03*
Y1345843D03*
Y1340843D03*
X61888Y666012D03*
X57124Y675327D03*
X54483Y679810D03*
X59236Y670758D03*
X70865Y872278D03*
Y866278D03*
Y860278D03*
Y897750D03*
Y890116D03*
X61866Y1309190D03*
X54543Y1308995D03*
X67568Y1307829D03*
X61866Y1342104D03*
X95775Y751469D03*
X89338Y878294D03*
X91733Y899382D03*
X92633Y907404D03*
X91294Y926951D03*
X98139Y990959D03*
X82763Y1060051D03*
X96684Y1081791D03*
X96510Y1395382D03*
X106958Y26285D03*
X107405Y49898D03*
X107037Y34687D03*
X106836Y376461D03*
X106709Y391219D03*
X107025Y725368D03*
X106935Y745139D03*
X107173Y735219D03*
X100687Y999391D03*
X107351Y1093484D03*
X107235Y1081791D03*
X107215Y1072208D03*
X105152Y1118381D03*
X100719Y1312810D03*
Y1306810D03*
Y1330810D03*
Y1336810D03*
Y1324810D03*
Y1318810D03*
Y1346065D03*
X106962Y1434041D03*
X106921Y1419492D03*
X106763Y1444599D03*
X107006Y1452651D03*
X107355Y1770437D03*
X107220Y1791589D03*
X107373Y1780544D03*
X106819Y1802230D03*
X144878Y1738861D03*
X157558Y51426D03*
X156865Y401207D03*
X156610Y751063D03*
X156854Y1101031D03*
X158618Y1399448D03*
X164037Y1400226D03*
X170351Y1401324D03*
X159192Y1451105D03*
X163257Y1737619D03*
X150309Y1737009D03*
X168151Y1739208D03*
X165782Y1732903D03*
X156183Y1735240D03*
X156452Y1800821D03*
X175989Y944537D03*
X176011Y936829D03*
X175359Y963486D03*
X175561Y955964D03*
X175135Y972490D03*
X175022Y980281D03*
X175742Y989958D03*
X175449Y997660D03*
X175698Y1008730D03*
X175473Y1016296D03*
X175448Y1031766D03*
X175897Y1023997D03*
X176083Y1402321D03*
X173394Y1736051D03*
X256947Y128276D03*
X257125Y115559D03*
X263086Y147675D03*
X265722Y463102D03*
X265737Y473680D03*
X264516Y497341D03*
X255837Y823626D03*
X255687Y812192D03*
X264181Y847354D03*
X262559Y1191777D03*
X271943Y147630D03*
X271547Y260353D03*
X281193Y256624D03*
X281074Y322688D03*
X289895D03*
X281569Y436169D03*
X291002Y432844D03*
X273405Y497341D03*
X285348Y610540D03*
X270109Y672192D03*
X278955D03*
X273114Y785968D03*
X282737Y782643D03*
X273305Y847237D03*
X285966Y959767D03*
X281124Y1016162D03*
X290107D03*
X282958Y1134471D03*
X272082Y1191777D03*
X283808Y1308959D03*
X279518Y1374543D03*
X270579Y1374626D03*
X279990Y1479435D03*
X270234Y1482760D03*
X291054Y1543211D03*
X284086Y1659883D03*
X284583Y1723465D03*
X274704Y1723196D03*
X281066Y1834569D03*
X291550Y1829846D03*
X280240Y1858668D03*
X279976Y1864565D03*
X282717Y1898327D03*
X273817D03*
X304151Y78778D03*
X313089D03*
X294483Y82732D03*
X308057Y248863D03*
X306267Y241010D03*
X314914Y238162D03*
X314940Y252083D03*
X295509Y607215D03*
X295874Y956442D03*
X309678Y1053262D03*
X292698Y1131146D03*
X312527Y1162266D03*
X312698Y1172804D03*
X294133Y1305634D03*
X314183Y1403423D03*
X302267Y1524401D03*
X301734Y1513883D03*
X300392Y1543211D03*
X312077Y1575871D03*
X294090Y1656558D03*
X314562Y2009087D03*
X331403Y51409D03*
X333889Y56021D03*
X338227Y61559D03*
X322005Y78778D03*
X320372Y225979D03*
X318088Y231820D03*
X321899Y238137D03*
X331046Y232021D03*
X320961Y250105D03*
X324709Y231580D03*
X335522Y404033D03*
X323313Y418313D03*
X326196Y413982D03*
X328950Y409216D03*
X320980Y423225D03*
X336617Y577978D03*
X319305Y582111D03*
X329636Y584715D03*
X317724Y588250D03*
X337387Y586230D03*
X320380Y576491D03*
X331867Y589810D03*
X333750Y595326D03*
X321742Y599041D03*
X331568Y752967D03*
X339012Y752859D03*
X329336Y762693D03*
X334010Y758588D03*
X327524Y758020D03*
X329938Y948756D03*
X332527Y943746D03*
X324098Y946104D03*
X318557Y941178D03*
X323868Y929978D03*
X326646Y939788D03*
X336160Y937262D03*
X328583Y933262D03*
X321425Y951577D03*
X324246Y1051786D03*
X335677Y1048904D03*
X317592Y1053050D03*
X337509Y1109598D03*
X328989Y1121090D03*
X326558Y1126368D03*
X327452Y1279447D03*
X321978Y1282086D03*
X329619Y1284016D03*
X327932Y1289221D03*
X325636Y1399114D03*
X334646Y1400804D03*
X323720Y1570924D03*
X333474Y1566686D03*
X335963Y1573797D03*
X323813Y1753231D03*
X329887Y1752081D03*
X332399Y1926787D03*
X324803Y2005272D03*
X359931Y52189D03*
X348289Y50863D03*
X345089Y56190D03*
X340373Y51579D03*
X362227Y299380D03*
X356831Y299956D03*
X360533Y339095D03*
X342097Y401684D03*
X363825Y401768D03*
X342900Y580126D03*
X364353Y650514D03*
X358911Y650530D03*
X347227Y694078D03*
X352358Y698363D03*
X362531Y694417D03*
X362577Y752783D03*
X344109Y751809D03*
X343656Y933725D03*
X345578Y1047844D03*
X344099Y1106798D03*
X344130Y1401670D03*
X350690Y1403243D03*
X348710Y1570187D03*
X361011Y1568890D03*
X343402Y1572080D03*
X348245Y1575241D03*
X355364Y1570990D03*
X361039Y1875684D03*
X353250Y1874308D03*
X347105Y1875191D03*
X345537Y1916558D03*
X344402Y1911123D03*
X353726Y1914205D03*
X360118Y1912411D03*
X363361Y1918313D03*
X358318Y1920680D03*
X363411Y1923459D03*
X340336Y1922409D03*
X372204Y56126D03*
X379257Y52158D03*
X387524Y76847D03*
X373942Y300523D03*
X368544Y300470D03*
X367076Y340100D03*
X374442Y406857D03*
X374542Y401282D03*
X368907Y404308D03*
X368680Y694668D03*
X376654Y754748D03*
X382892Y767710D03*
X386790Y774338D03*
X379335Y1189778D03*
X383276Y1184136D03*
X386816Y1179841D03*
X376472Y1194999D03*
X373674Y1199967D03*
X371523Y1204725D03*
X385261Y1334686D03*
X378904Y1333844D03*
X381725Y1340790D03*
X373499Y1340730D03*
X377984Y1383142D03*
X380378Y1377228D03*
X367829Y1566108D03*
X365922Y1870477D03*
X374431Y1901397D03*
X374775Y1919243D03*
X379403Y1917261D03*
X369748Y1921795D03*
G54D25*
X385146Y333689D03*
Y330539D03*
X380915Y333668D03*
Y330518D03*
G54D16*
X45056Y1817693D03*
G54D26*
X379000Y672905D03*
X375850D03*
X384867Y1377774D03*
X388017D03*
X381927Y1901748D03*
X378777D03*
G54D17*
X64979Y35500D03*
Y45500D03*
Y55500D03*
X54979Y40500D03*
Y50500D03*
X64979Y65500D03*
X54979Y60500D03*
X64979Y171500D03*
X54979Y176500D03*
X64979Y181500D03*
Y191500D03*
Y201500D03*
X54979Y186500D03*
Y196500D03*
X64979Y244500D03*
X54979Y249500D03*
X64979Y254500D03*
Y264500D03*
Y274500D03*
X54979Y259500D03*
Y269500D03*
X64979Y380500D03*
Y390500D03*
X54979Y385500D03*
Y395500D03*
X64979Y400500D03*
Y410500D03*
X54979Y405500D03*
X189762Y73105D03*
X190289Y152050D03*
X190357Y247568D03*
X190817Y331786D03*
X189761Y421732D03*
X190553Y506517D03*
X192888Y598130D03*
X190816Y681645D03*
X191846Y774526D03*
X191606Y856244D03*
X196311Y947202D03*
X195516Y1032544D03*
X191250Y1122856D03*
X191342Y1206233D03*
X191846Y1299104D03*
X190552Y1380966D03*
X189463Y1474162D03*
X191079Y1557277D03*
X192143Y1648177D03*
X191607Y1731351D03*
X191530Y1823227D03*
X190289Y1900420D03*
X192125Y1998730D03*
X191530Y2043388D03*
G54D27*
G01X-723776Y2987387D02*
Y-376795D01*
Y-489221D01*
X1782976D01*
Y-376795D01*
Y2987387D01*
X-723776D01*
G01X-4000Y-62500D02*
Y-137500D01*
X496000D01*
Y-62500D01*
X-4000D01*
G01X8000Y-127500D02*
Y-132500D01*
G01X6543Y-127500D02*
X9457D01*
G01X14367Y-132500D02*
X11833D01*
Y-127500D01*
X14367D01*
G01X13353Y-129917D02*
X11833D01*
G01X16933Y-127500D02*
Y-132500D01*
X19467D01*
G01X23300Y-132667D02*
X23173Y-132583D01*
Y-132417D01*
X23300Y-132333D01*
X23427Y-132417D01*
Y-132583D01*
X23300Y-132667D01*
G01Y-130417D02*
X23173Y-130333D01*
Y-130167D01*
X23300Y-130083D01*
X23427Y-130167D01*
Y-130333D01*
X23300Y-130417D01*
G01X28083Y-134167D02*
X27450Y-133333D01*
X27133Y-132500D01*
Y-129167D01*
X27450Y-128333D01*
X28083Y-127500D01*
G01X33500D02*
X32993Y-127667D01*
X32613Y-128083D01*
X32360Y-128583D01*
X32170Y-129250D01*
X32107Y-130000D01*
X32170Y-130750D01*
X32360Y-131417D01*
X32613Y-131917D01*
X32993Y-132333D01*
X33500Y-132500D01*
X34007Y-132333D01*
X34387Y-131917D01*
X34640Y-131417D01*
X34830Y-130750D01*
X34893Y-130000D01*
X34830Y-129250D01*
X34640Y-128583D01*
X34387Y-128083D01*
X34007Y-127667D01*
X33500Y-127500D01*
G01X37207Y-131500D02*
X37587Y-132083D01*
X38093Y-132417D01*
X38663Y-132500D01*
X39170Y-132417D01*
X39677Y-132000D01*
X39993Y-131500D01*
X40057Y-131000D01*
X39930Y-130417D01*
X39487Y-130000D01*
X39043Y-129833D01*
X38473D01*
G01X39043D02*
X39423Y-129583D01*
X39740Y-129167D01*
X39867Y-128667D01*
X39740Y-128167D01*
X39423Y-127750D01*
X38853Y-127500D01*
X38283Y-127583D01*
X37713Y-127917D01*
G01X44017Y-134167D02*
X44650Y-133333D01*
X44967Y-132500D01*
Y-129167D01*
X44650Y-128333D01*
X44017Y-127500D01*
G01X47407Y-131500D02*
X47787Y-132083D01*
X48293Y-132417D01*
X48863Y-132500D01*
X49370Y-132417D01*
X49877Y-132000D01*
X50193Y-131500D01*
X50257Y-131000D01*
X50130Y-130417D01*
X49687Y-130000D01*
X49243Y-129833D01*
X48673D01*
G01X49243D02*
X49623Y-129583D01*
X49940Y-129167D01*
X50067Y-128667D01*
X49940Y-128167D01*
X49623Y-127750D01*
X49053Y-127500D01*
X48483Y-127583D01*
X47913Y-127917D01*
G01X52697Y-128333D02*
X53077Y-127833D01*
X53520Y-127583D01*
X54027Y-127500D01*
X54660Y-127667D01*
X55103Y-128083D01*
X55230Y-128583D01*
X55167Y-129083D01*
X54913Y-129500D01*
X53647Y-130333D01*
X53077Y-130917D01*
X52697Y-131750D01*
X52570Y-132500D01*
X55230D01*
G01X58873D02*
X59000Y-131417D01*
X59190Y-130500D01*
X59443Y-129667D01*
X59760Y-128750D01*
X60267Y-127500D01*
X57733D01*
G01X63277Y-130833D02*
X64923D01*
G01X67997Y-128333D02*
X68377Y-127833D01*
X68820Y-127583D01*
X69327Y-127500D01*
X69960Y-127667D01*
X70403Y-128083D01*
X70530Y-128583D01*
X70467Y-129083D01*
X70213Y-129500D01*
X68947Y-130333D01*
X68377Y-130917D01*
X67997Y-131750D01*
X67870Y-132500D01*
X70530D01*
G01X72907Y-131500D02*
X73287Y-132083D01*
X73793Y-132417D01*
X74363Y-132500D01*
X74870Y-132417D01*
X75377Y-132000D01*
X75693Y-131500D01*
X75757Y-131000D01*
X75630Y-130417D01*
X75187Y-130000D01*
X74743Y-129833D01*
X74173D01*
G01X74743D02*
X75123Y-129583D01*
X75440Y-129167D01*
X75567Y-128667D01*
X75440Y-128167D01*
X75123Y-127750D01*
X74553Y-127500D01*
X73983Y-127583D01*
X73413Y-127917D01*
G01X80160Y-132500D02*
Y-127500D01*
X77817Y-131083D01*
X80983D01*
G01X83107Y-131750D02*
X83487Y-132167D01*
X83930Y-132417D01*
X84500Y-132500D01*
X85070Y-132333D01*
X85513Y-132000D01*
X85830Y-131417D01*
X85893Y-130750D01*
X85767Y-130083D01*
X85450Y-129667D01*
X85007Y-129333D01*
X84563Y-129250D01*
X84120Y-129333D01*
X83550Y-129667D01*
X83740Y-127500D01*
X85450D01*
G01X93497Y-132500D02*
Y-127500D01*
X95903D01*
G01X95017Y-129917D02*
X93497D01*
G01X98217Y-132500D02*
X99800Y-127500D01*
X101383Y-132500D01*
G01X100813Y-130750D02*
X98787D01*
G01X103570Y-132500D02*
X106230Y-127500D01*
G01X103570D02*
X106230Y-132500D01*
G01X110000Y-132667D02*
X109873Y-132583D01*
Y-132417D01*
X110000Y-132333D01*
X110127Y-132417D01*
Y-132583D01*
X110000Y-132667D01*
G01Y-130417D02*
X109873Y-130333D01*
Y-130167D01*
X110000Y-130083D01*
X110127Y-130167D01*
Y-130333D01*
X110000Y-130417D01*
G01X114783Y-134167D02*
X114150Y-133333D01*
X113833Y-132500D01*
Y-129167D01*
X114150Y-128333D01*
X114783Y-127500D01*
G01X120200D02*
X119693Y-127667D01*
X119313Y-128083D01*
X119060Y-128583D01*
X118870Y-129250D01*
X118807Y-130000D01*
X118870Y-130750D01*
X119060Y-131417D01*
X119313Y-131917D01*
X119693Y-132333D01*
X120200Y-132500D01*
X120707Y-132333D01*
X121087Y-131917D01*
X121340Y-131417D01*
X121530Y-130750D01*
X121593Y-130000D01*
X121530Y-129250D01*
X121340Y-128583D01*
X121087Y-128083D01*
X120707Y-127667D01*
X120200Y-127500D01*
G01X123907Y-131500D02*
X124287Y-132083D01*
X124793Y-132417D01*
X125363Y-132500D01*
X125870Y-132417D01*
X126377Y-132000D01*
X126693Y-131500D01*
X126757Y-131000D01*
X126630Y-130417D01*
X126187Y-130000D01*
X125743Y-129833D01*
X125173D01*
G01X125743D02*
X126123Y-129583D01*
X126440Y-129167D01*
X126567Y-128667D01*
X126440Y-128167D01*
X126123Y-127750D01*
X125553Y-127500D01*
X124983Y-127583D01*
X124413Y-127917D01*
G01X130717Y-134167D02*
X131350Y-133333D01*
X131667Y-132500D01*
Y-129167D01*
X131350Y-128333D01*
X130717Y-127500D01*
G01X134107Y-131500D02*
X134487Y-132083D01*
X134993Y-132417D01*
X135563Y-132500D01*
X136070Y-132417D01*
X136577Y-132000D01*
X136893Y-131500D01*
X136957Y-131000D01*
X136830Y-130417D01*
X136387Y-130000D01*
X135943Y-129833D01*
X135373D01*
G01X135943D02*
X136323Y-129583D01*
X136640Y-129167D01*
X136767Y-128667D01*
X136640Y-128167D01*
X136323Y-127750D01*
X135753Y-127500D01*
X135183Y-127583D01*
X134613Y-127917D01*
G01X139523Y-131917D02*
X139967Y-132333D01*
X140473Y-132500D01*
X140980Y-132333D01*
X141423Y-131833D01*
X141740Y-131083D01*
X141867Y-130333D01*
Y-129417D01*
X141740Y-128667D01*
X141423Y-128000D01*
X141043Y-127667D01*
X140600Y-127500D01*
X140093Y-127667D01*
X139713Y-128000D01*
X139460Y-128500D01*
X139333Y-129167D01*
X139460Y-129750D01*
X139777Y-130333D01*
X140157Y-130667D01*
X140600Y-130750D01*
X141107Y-130583D01*
X141487Y-130167D01*
X141867Y-129417D01*
G01X145573Y-132500D02*
X145700Y-131417D01*
X145890Y-130500D01*
X146143Y-129667D01*
X146460Y-128750D01*
X146967Y-127500D01*
X144433D01*
G01X149977Y-130833D02*
X151623D01*
G01X154507Y-131500D02*
X154887Y-132083D01*
X155393Y-132417D01*
X155963Y-132500D01*
X156470Y-132417D01*
X156977Y-132000D01*
X157293Y-131500D01*
X157357Y-131000D01*
X157230Y-130417D01*
X156787Y-130000D01*
X156343Y-129833D01*
X155773D01*
G01X156343D02*
X156723Y-129583D01*
X157040Y-129167D01*
X157167Y-128667D01*
X157040Y-128167D01*
X156723Y-127750D01*
X156153Y-127500D01*
X155583Y-127583D01*
X155013Y-127917D01*
G01X159797Y-130417D02*
X160240Y-129833D01*
X160620Y-129500D01*
X161127Y-129333D01*
X161570Y-129500D01*
X161887Y-129833D01*
X162140Y-130333D01*
X162203Y-130917D01*
X162140Y-131417D01*
X161887Y-131917D01*
X161507Y-132333D01*
X161063Y-132500D01*
X160557Y-132333D01*
X160113Y-131833D01*
X159860Y-131083D01*
X159797Y-130250D01*
X159923Y-129167D01*
X160113Y-128583D01*
X160430Y-128000D01*
X160873Y-127583D01*
X161317Y-127500D01*
X161760Y-127667D01*
X162077Y-128083D01*
G01X166100Y-132500D02*
Y-127500D01*
X165340Y-128500D01*
G01Y-132500D02*
X166860D01*
G01X171960D02*
Y-127500D01*
X169617Y-131083D01*
X172783D01*
G01X191000Y-62500D02*
Y-137500D01*
G01Y-112500D02*
X294000D01*
Y-87500D01*
G01X191000D02*
X294000D01*
G01X301507Y-122500D02*
Y-117500D01*
X302773D01*
X303280Y-117750D01*
X303660Y-118083D01*
X303977Y-118583D01*
X304230Y-119167D01*
X304293Y-120000D01*
X304230Y-120833D01*
X303977Y-121417D01*
X303660Y-121917D01*
X303280Y-122250D01*
X302773Y-122500D01*
X301507D01*
G01X306417D02*
X308000Y-117500D01*
X309583Y-122500D01*
G01X309013Y-120750D02*
X306987D01*
G01X313100Y-117500D02*
Y-122500D01*
G01X311643Y-117500D02*
X314557D01*
G01X319467Y-122500D02*
X316933D01*
Y-117500D01*
X319467D01*
G01X318453Y-119917D02*
X316933D01*
G01X323300Y-122667D02*
X323173Y-122583D01*
Y-122417D01*
X323300Y-122333D01*
X323427Y-122417D01*
Y-122583D01*
X323300Y-122667D01*
G01Y-120417D02*
X323173Y-120333D01*
Y-120167D01*
X323300Y-120083D01*
X323427Y-120167D01*
Y-120333D01*
X323300Y-120417D01*
G01X296000Y-62500D02*
Y-137500D01*
G01X294000Y-62500D02*
Y-137500D01*
G01X301633Y-97500D02*
Y-92500D01*
X303153D01*
X303660Y-92750D01*
X304040Y-93333D01*
X304167Y-94000D01*
X304040Y-94667D01*
X303723Y-95167D01*
X303153Y-95417D01*
X301633D01*
G01X306860Y-97667D02*
X309140Y-92500D01*
G01X311643Y-97500D02*
Y-92500D01*
X314557Y-97500D01*
Y-92500D01*
G01X318200Y-97667D02*
X318073Y-97583D01*
Y-97417D01*
X318200Y-97333D01*
X318327Y-97417D01*
Y-97583D01*
X318200Y-97667D01*
G01Y-95417D02*
X318073Y-95333D01*
Y-95167D01*
X318200Y-95083D01*
X318327Y-95167D01*
Y-95333D01*
X318200Y-95417D01*
G01X296000Y-112500D02*
X496000D01*
G01X301633Y-72500D02*
Y-67500D01*
X303153D01*
X303660Y-67750D01*
X304040Y-68333D01*
X304167Y-69000D01*
X304040Y-69667D01*
X303723Y-70167D01*
X303153Y-70417D01*
X301633D01*
G01X306733Y-72500D02*
Y-67500D01*
X308317D01*
X308823Y-67750D01*
X309140Y-68083D01*
X309267Y-68750D01*
X309140Y-69417D01*
X308760Y-69833D01*
X308317Y-70083D01*
X306733D01*
G01X308317D02*
X309267Y-72500D01*
G01X313100D02*
X312593Y-72417D01*
X312150Y-72083D01*
X311770Y-71583D01*
X311517Y-71000D01*
X311390Y-70333D01*
Y-69667D01*
X311517Y-69000D01*
X311770Y-68417D01*
X312150Y-67917D01*
X312593Y-67583D01*
X313100Y-67500D01*
X313607Y-67583D01*
X314050Y-67917D01*
X314430Y-68417D01*
X314683Y-69000D01*
X314810Y-69667D01*
Y-70333D01*
X314683Y-71000D01*
X314430Y-71583D01*
X314050Y-72083D01*
X313607Y-72417D01*
X313100Y-72500D01*
G01X316933Y-71500D02*
X317250Y-72000D01*
X317630Y-72333D01*
X318073Y-72500D01*
X318580Y-72333D01*
X318960Y-72000D01*
X319340Y-71500D01*
X319467Y-70833D01*
Y-67500D01*
G01X324567Y-72500D02*
X322033D01*
Y-67500D01*
X324567D01*
G01X323553Y-69917D02*
X322033D01*
G01X329793Y-67917D02*
X329413Y-67667D01*
X328970Y-67500D01*
X328463D01*
X327893Y-67750D01*
X327450Y-68167D01*
X327133Y-68667D01*
X326880Y-69500D01*
X326817Y-70250D01*
X326943Y-71000D01*
X327133Y-71500D01*
X327513Y-72000D01*
X327957Y-72333D01*
X328400Y-72500D01*
X328843D01*
X329287Y-72333D01*
X329667Y-72083D01*
X329983Y-71750D01*
G01X333500Y-67500D02*
Y-72500D01*
G01X332043Y-67500D02*
X334957D01*
G01X338600Y-72667D02*
X338473Y-72583D01*
Y-72417D01*
X338600Y-72333D01*
X338727Y-72417D01*
Y-72583D01*
X338600Y-72667D01*
G01Y-70417D02*
X338473Y-70333D01*
Y-70167D01*
X338600Y-70083D01*
X338727Y-70167D01*
Y-70333D01*
X338600Y-70417D01*
G01X296000Y-87500D02*
X496000D01*
G01X411000Y-112500D02*
Y-137500D01*
G01X416633Y-122500D02*
Y-117500D01*
X418217D01*
X418723Y-117750D01*
X419040Y-118083D01*
X419167Y-118750D01*
X419040Y-119417D01*
X418660Y-119833D01*
X418217Y-120083D01*
X416633D01*
G01X418217D02*
X419167Y-122500D01*
G01X424267D02*
X421733D01*
Y-117500D01*
X424267D01*
G01X423253Y-119917D02*
X421733D01*
G01X426517Y-117500D02*
X428100Y-122500D01*
X429683Y-117500D01*
G01X433200Y-122667D02*
X433073Y-122583D01*
Y-122417D01*
X433200Y-122333D01*
X433327Y-122417D01*
Y-122583D01*
X433200Y-122667D01*
G01Y-120417D02*
X433073Y-120333D01*
Y-120167D01*
X433200Y-120083D01*
X433327Y-120167D01*
Y-120333D01*
X433200Y-120417D01*
G01X460000Y-112500D02*
Y-137500D01*
G01X-723776Y2987387D02*
Y-376795D01*
Y-489221D01*
X1782976D01*
Y-376795D01*
Y2987387D01*
X-723776D01*
G01X6705Y-124160D02*
X7332Y-124685D01*
X8037Y-125000D01*
X8663D01*
X9290Y-124685D01*
X9760Y-124160D01*
X9995Y-123425D01*
X9838Y-122690D01*
X9447Y-122060D01*
X8742Y-121640D01*
X7802Y-121430D01*
X7253Y-121010D01*
X7018Y-120275D01*
X7175Y-119540D01*
X7567Y-119015D01*
X8115Y-118700D01*
X8663D01*
X9212Y-118910D01*
X9682Y-119435D01*
G01X13005Y-125000D02*
Y-118700D01*
G01X16295D02*
Y-125000D01*
G01Y-121850D02*
X13005D01*
G01X20010Y-118700D02*
X21890D01*
G01X20950D02*
Y-125000D01*
G01X20010D02*
X21890D01*
G01X28817D02*
X25683D01*
Y-118700D01*
X28817D01*
G01X27563Y-121745D02*
X25683D01*
G01X31748Y-125000D02*
Y-118700D01*
X35352Y-125000D01*
Y-118700D01*
G01X39693Y-126155D02*
X40007Y-124790D01*
G01X46150Y-118700D02*
Y-125000D01*
G01X44348Y-118700D02*
X47952D01*
G01X50492Y-125000D02*
X52450Y-118700D01*
X54408Y-125000D01*
G01X53703Y-122795D02*
X51197D01*
G01X57810Y-118700D02*
X59690D01*
G01X58750D02*
Y-125000D01*
G01X57810D02*
X59690D01*
G01X62700Y-118700D02*
X63797Y-125000D01*
X65050Y-118700D01*
X66303Y-125000D01*
X67400Y-118700D01*
G01X69392Y-125000D02*
X71350Y-118700D01*
X73308Y-125000D01*
G01X72603Y-122795D02*
X70097D01*
G01X75848Y-125000D02*
Y-118700D01*
X79452Y-125000D01*
Y-118700D01*
G01X88683Y-125000D02*
Y-118700D01*
X90642D01*
X91268Y-119015D01*
X91660Y-119435D01*
X91817Y-120275D01*
X91660Y-121115D01*
X91190Y-121640D01*
X90642Y-121955D01*
X88683D01*
G01X90642D02*
X91817Y-125000D01*
G01X96550Y-125210D02*
X96393Y-125105D01*
Y-124895D01*
X96550Y-124790D01*
X96707Y-124895D01*
Y-125105D01*
X96550Y-125210D01*
G01X102850Y-125000D02*
X102223Y-124895D01*
X101675Y-124475D01*
X101205Y-123845D01*
X100892Y-123110D01*
X100735Y-122270D01*
Y-121430D01*
X100892Y-120590D01*
X101205Y-119855D01*
X101675Y-119225D01*
X102223Y-118805D01*
X102850Y-118700D01*
X103477Y-118805D01*
X104025Y-119225D01*
X104495Y-119855D01*
X104808Y-120590D01*
X104965Y-121430D01*
Y-122270D01*
X104808Y-123110D01*
X104495Y-123845D01*
X104025Y-124475D01*
X103477Y-124895D01*
X102850Y-125000D01*
G01X109150Y-125210D02*
X108993Y-125105D01*
Y-124895D01*
X109150Y-124790D01*
X109307Y-124895D01*
Y-125105D01*
X109150Y-125210D01*
G01X117173Y-119225D02*
X116703Y-118910D01*
X116155Y-118700D01*
X115528D01*
X114823Y-119015D01*
X114275Y-119540D01*
X113883Y-120170D01*
X113570Y-121220D01*
X113492Y-122165D01*
X113648Y-123110D01*
X113883Y-123740D01*
X114353Y-124370D01*
X114902Y-124790D01*
X115450Y-125000D01*
X115998D01*
X116547Y-124790D01*
X117017Y-124475D01*
X117408Y-124055D01*
G01X121750Y-125210D02*
X121593Y-125105D01*
Y-124895D01*
X121750Y-124790D01*
X121907Y-124895D01*
Y-125105D01*
X121750Y-125210D01*
G01X6627Y-115000D02*
Y-108700D01*
G01X9603D02*
X6627Y-112585D01*
G01X10073Y-115000D02*
X7958Y-110800D01*
G01X12927Y-108700D02*
Y-113215D01*
X13240Y-114160D01*
X13867Y-114790D01*
X14650Y-115000D01*
X15433Y-114790D01*
X16060Y-114160D01*
X16373Y-113215D01*
Y-108700D01*
G01X22517Y-115000D02*
X19383D01*
Y-108700D01*
X22517D01*
G01X21263Y-111745D02*
X19383D01*
G01X26310Y-108700D02*
X28190D01*
G01X27250D02*
Y-115000D01*
G01X26310D02*
X28190D01*
G01X38205Y-114160D02*
X38832Y-114685D01*
X39537Y-115000D01*
X40163D01*
X40790Y-114685D01*
X41260Y-114160D01*
X41495Y-113425D01*
X41338Y-112690D01*
X40947Y-112060D01*
X40242Y-111640D01*
X39302Y-111430D01*
X38753Y-111010D01*
X38518Y-110275D01*
X38675Y-109540D01*
X39067Y-109015D01*
X39615Y-108700D01*
X40163D01*
X40712Y-108910D01*
X41182Y-109435D01*
G01X44505Y-115000D02*
Y-108700D01*
G01X47795D02*
Y-115000D01*
G01Y-111850D02*
X44505D01*
G01X50492Y-115000D02*
X52450Y-108700D01*
X54408Y-115000D01*
G01X53703Y-112795D02*
X51197D01*
G01X56948Y-115000D02*
Y-108700D01*
X60552Y-115000D01*
Y-108700D01*
G01X69705Y-115000D02*
Y-108700D01*
G01X72995D02*
Y-115000D01*
G01Y-111850D02*
X69705D01*
G01X76005Y-114160D02*
X76632Y-114685D01*
X77337Y-115000D01*
X77963D01*
X78590Y-114685D01*
X79060Y-114160D01*
X79295Y-113425D01*
X79138Y-112690D01*
X78747Y-112060D01*
X78042Y-111640D01*
X77102Y-111430D01*
X76553Y-111010D01*
X76318Y-110275D01*
X76475Y-109540D01*
X76867Y-109015D01*
X77415Y-108700D01*
X77963D01*
X78512Y-108910D01*
X78982Y-109435D01*
G01X83010Y-108700D02*
X84890D01*
G01X83950D02*
Y-115000D01*
G01X83010D02*
X84890D01*
G01X88292D02*
X90250Y-108700D01*
X92208Y-115000D01*
G01X91503Y-112795D02*
X88997D01*
G01X94748Y-115000D02*
Y-108700D01*
X98352Y-115000D01*
Y-108700D01*
G01X103320Y-111850D02*
X104887D01*
Y-113740D01*
X104417Y-114370D01*
X103868Y-114790D01*
X103085Y-115000D01*
X102302Y-114790D01*
X101753Y-114370D01*
X101283Y-113740D01*
X100970Y-113005D01*
X100813Y-112165D01*
Y-111430D01*
X100970Y-110800D01*
X101283Y-110065D01*
X101753Y-109435D01*
X102223Y-109015D01*
X102850Y-108700D01*
X103398D01*
X104025Y-108910D01*
X104495Y-109330D01*
G01X108993Y-116155D02*
X109307Y-114790D01*
G01X115450Y-108700D02*
Y-115000D01*
G01X113648Y-108700D02*
X117252D01*
G01X119792Y-115000D02*
X121750Y-108700D01*
X123708Y-115000D01*
G01X123003Y-112795D02*
X120497D01*
G01X128050Y-115000D02*
X127423Y-114895D01*
X126875Y-114475D01*
X126405Y-113845D01*
X126092Y-113110D01*
X125935Y-112270D01*
Y-111430D01*
X126092Y-110590D01*
X126405Y-109855D01*
X126875Y-109225D01*
X127423Y-108805D01*
X128050Y-108700D01*
X128677Y-108805D01*
X129225Y-109225D01*
X129695Y-109855D01*
X130008Y-110590D01*
X130165Y-111430D01*
Y-112270D01*
X130008Y-113110D01*
X129695Y-113845D01*
X129225Y-114475D01*
X128677Y-114895D01*
X128050Y-115000D01*
G01X140650D02*
Y-112165D01*
X139083Y-108700D01*
G01X142217D02*
X140650Y-112165D01*
G01X145227Y-108700D02*
Y-113215D01*
X145540Y-114160D01*
X146167Y-114790D01*
X146950Y-115000D01*
X147733Y-114790D01*
X148360Y-114160D01*
X148673Y-113215D01*
Y-108700D01*
G01X151292Y-115000D02*
X153250Y-108700D01*
X155208Y-115000D01*
G01X154503Y-112795D02*
X151997D01*
G01X157748Y-115000D02*
Y-108700D01*
X161352Y-115000D01*
Y-108700D01*
G01X30650Y-92300D02*
X28130Y-91883D01*
X25925Y-90217D01*
X24035Y-87717D01*
X22775Y-84800D01*
X22145Y-81467D01*
Y-78133D01*
X22775Y-74800D01*
X24035Y-71883D01*
X25925Y-69384D01*
X28130Y-67717D01*
X30650Y-67300D01*
X33170Y-67717D01*
X35375Y-69384D01*
X37265Y-71883D01*
X38525Y-74800D01*
X39155Y-78133D01*
Y-81467D01*
X38525Y-84800D01*
X37265Y-87717D01*
X35375Y-90217D01*
X33170Y-91883D01*
X30650Y-92300D01*
G01X33170Y-85633D02*
X36950Y-92300D01*
G01X50495Y-75634D02*
Y-87300D01*
X51755Y-90217D01*
X53645Y-91883D01*
X55850Y-92300D01*
X58055Y-91883D01*
X59945Y-90217D01*
X61205Y-87300D01*
G01Y-92300D02*
Y-75634D01*
G01X86720Y-92300D02*
Y-75634D01*
G01Y-78550D02*
X85460Y-76884D01*
X83570Y-76050D01*
X81365Y-75634D01*
X79160Y-76467D01*
X77270Y-78133D01*
X76010Y-80634D01*
X75380Y-83967D01*
X76010Y-87300D01*
X77270Y-89801D01*
X79160Y-91467D01*
X81365Y-92300D01*
X83570Y-91883D01*
X85460Y-90634D01*
X86720Y-88967D01*
G01X100895Y-92300D02*
Y-75634D01*
G01Y-79800D02*
X102155Y-77717D01*
X104045Y-76050D01*
X106565Y-75634D01*
X108770Y-76050D01*
X110660Y-77717D01*
X111605Y-80634D01*
Y-92300D01*
G01X131450Y-67300D02*
Y-92300D01*
G01X127040Y-75634D02*
X135860D01*
G01X162320Y-92300D02*
Y-75634D01*
G01Y-78550D02*
X161060Y-76884D01*
X159170Y-76050D01*
X156965Y-75634D01*
X154760Y-76467D01*
X152870Y-78133D01*
X151610Y-80634D01*
X150980Y-83967D01*
X151610Y-87300D01*
X152870Y-89801D01*
X154760Y-91467D01*
X156965Y-92300D01*
X159170Y-91883D01*
X161060Y-90634D01*
X162320Y-88967D01*
G01X6548Y-105000D02*
Y-98700D01*
X10152Y-105000D01*
Y-98700D01*
G01X14650Y-105000D02*
X14023Y-104895D01*
X13475Y-104475D01*
X13005Y-103845D01*
X12692Y-103110D01*
X12535Y-102270D01*
Y-101430D01*
X12692Y-100590D01*
X13005Y-99855D01*
X13475Y-99225D01*
X14023Y-98805D01*
X14650Y-98700D01*
X15277Y-98805D01*
X15825Y-99225D01*
X16295Y-99855D01*
X16608Y-100590D01*
X16765Y-101430D01*
Y-102270D01*
X16608Y-103110D01*
X16295Y-103845D01*
X15825Y-104475D01*
X15277Y-104895D01*
X14650Y-105000D01*
G01X20950Y-105210D02*
X20793Y-105105D01*
Y-104895D01*
X20950Y-104790D01*
X21107Y-104895D01*
Y-105105D01*
X20950Y-105210D01*
G01X27250Y-105000D02*
Y-98700D01*
X26310Y-99960D01*
G01Y-105000D02*
X28190D01*
G01X33550D02*
X34098Y-104895D01*
X34725Y-104580D01*
X35117Y-104055D01*
X35273Y-103320D01*
X35117Y-102585D01*
X34647Y-101955D01*
X33942Y-101640D01*
X33158D01*
X32688Y-101430D01*
X32297Y-100905D01*
X32140Y-100170D01*
X32375Y-99435D01*
X32923Y-98910D01*
X33550Y-98700D01*
X34177Y-98910D01*
X34725Y-99435D01*
X34960Y-100170D01*
X34803Y-100905D01*
X34412Y-101430D01*
X33942Y-101640D01*
X33158D01*
X32453Y-101955D01*
X31983Y-102585D01*
X31827Y-103320D01*
X31983Y-104055D01*
X32375Y-104580D01*
X33002Y-104895D01*
X33550Y-105000D01*
G01X39850D02*
X40398Y-104895D01*
X41025Y-104580D01*
X41417Y-104055D01*
X41573Y-103320D01*
X41417Y-102585D01*
X40947Y-101955D01*
X40242Y-101640D01*
X39458D01*
X38988Y-101430D01*
X38597Y-100905D01*
X38440Y-100170D01*
X38675Y-99435D01*
X39223Y-98910D01*
X39850Y-98700D01*
X40477Y-98910D01*
X41025Y-99435D01*
X41260Y-100170D01*
X41103Y-100905D01*
X40712Y-101430D01*
X40242Y-101640D01*
X39458D01*
X38753Y-101955D01*
X38283Y-102585D01*
X38127Y-103320D01*
X38283Y-104055D01*
X38675Y-104580D01*
X39302Y-104895D01*
X39850Y-105000D01*
G01X45993Y-106155D02*
X46307Y-104790D01*
G01X50100Y-98700D02*
X51197Y-105000D01*
X52450Y-98700D01*
X53703Y-105000D01*
X54800Y-98700D01*
G01X60317Y-105000D02*
X57183D01*
Y-98700D01*
X60317D01*
G01X59063Y-101745D02*
X57183D01*
G01X63248Y-105000D02*
Y-98700D01*
X66852Y-105000D01*
Y-98700D01*
G01X76005Y-105000D02*
Y-98700D01*
G01X79295D02*
Y-105000D01*
G01Y-101850D02*
X76005D01*
G01X81600Y-98700D02*
X82697Y-105000D01*
X83950Y-98700D01*
X85203Y-105000D01*
X86300Y-98700D01*
G01X88292Y-105000D02*
X90250Y-98700D01*
X92208Y-105000D01*
G01X91503Y-102795D02*
X88997D01*
G01X101362Y-99750D02*
X101832Y-99120D01*
X102380Y-98805D01*
X103007Y-98700D01*
X103790Y-98910D01*
X104338Y-99435D01*
X104495Y-100065D01*
X104417Y-100695D01*
X104103Y-101220D01*
X102537Y-102270D01*
X101832Y-103005D01*
X101362Y-104055D01*
X101205Y-105000D01*
X104495D01*
G01X107348D02*
Y-98700D01*
X110952Y-105000D01*
Y-98700D01*
G01X113727Y-105000D02*
Y-98700D01*
X115293D01*
X115920Y-99015D01*
X116390Y-99435D01*
X116782Y-100065D01*
X117095Y-100800D01*
X117173Y-101850D01*
X117095Y-102900D01*
X116782Y-103635D01*
X116390Y-104265D01*
X115920Y-104685D01*
X115293Y-105000D01*
X113727D01*
G01X126483D02*
Y-98700D01*
X128442D01*
X129068Y-99015D01*
X129460Y-99435D01*
X129617Y-100275D01*
X129460Y-101115D01*
X128990Y-101640D01*
X128442Y-101955D01*
X126483D01*
G01X128442D02*
X129617Y-105000D01*
G01X132627D02*
Y-98700D01*
X134193D01*
X134820Y-99015D01*
X135290Y-99435D01*
X135682Y-100065D01*
X135995Y-100800D01*
X136073Y-101850D01*
X135995Y-102900D01*
X135682Y-103635D01*
X135290Y-104265D01*
X134820Y-104685D01*
X134193Y-105000D01*
X132627D01*
G01X140650Y-105210D02*
X140493Y-105105D01*
Y-104895D01*
X140650Y-104790D01*
X140807Y-104895D01*
Y-105105D01*
X140650Y-105210D01*
G01X213500Y-105000D02*
Y-97000D01*
X215900D01*
X216700Y-97400D01*
X217300Y-98333D01*
X217500Y-99400D01*
X217300Y-100467D01*
X216800Y-101267D01*
X215900Y-101667D01*
X213500D01*
G01X221000Y-105000D02*
X223500Y-97000D01*
X226000Y-105000D01*
G01X225100Y-102200D02*
X221900D01*
G01X229400Y-103934D02*
X230200Y-104600D01*
X231100Y-105000D01*
X231900D01*
X232700Y-104600D01*
X233300Y-103934D01*
X233600Y-103000D01*
X233400Y-102067D01*
X232900Y-101267D01*
X232000Y-100733D01*
X230800Y-100467D01*
X230100Y-99933D01*
X229800Y-99000D01*
X230000Y-98067D01*
X230500Y-97400D01*
X231200Y-97000D01*
X231900D01*
X232600Y-97267D01*
X233200Y-97933D01*
G01X239500Y-97000D02*
Y-105000D01*
G01X237200Y-97000D02*
X241800D01*
G01X246200Y-102333D02*
X248800D01*
G01X256300Y-100733D02*
X256700Y-100333D01*
X257000Y-99667D01*
X257200Y-98733D01*
X257000Y-97933D01*
X256600Y-97400D01*
X255900Y-97000D01*
X253200D01*
Y-105000D01*
X256500D01*
X257200Y-104467D01*
X257600Y-103667D01*
X257800Y-102733D01*
X257600Y-101800D01*
X257000Y-101000D01*
X256300Y-100733D01*
X253200D01*
G01X263500Y-105000D02*
X262700Y-104867D01*
X262000Y-104333D01*
X261400Y-103533D01*
X261000Y-102600D01*
X260800Y-101533D01*
Y-100467D01*
X261000Y-99400D01*
X261400Y-98467D01*
X262000Y-97667D01*
X262700Y-97133D01*
X263500Y-97000D01*
X264300Y-97133D01*
X265000Y-97667D01*
X265600Y-98467D01*
X266000Y-99400D01*
X266200Y-100467D01*
Y-101533D01*
X266000Y-102600D01*
X265600Y-103533D01*
X265000Y-104333D01*
X264300Y-104867D01*
X263500Y-105000D01*
G01X271500Y-97000D02*
Y-105000D01*
G01X269200Y-97000D02*
X273800D01*
G01X202000Y-72000D02*
Y-80000D01*
X206000D01*
G01X213800D02*
Y-74667D01*
G01Y-75600D02*
X213400Y-75067D01*
X212800Y-74800D01*
X212100Y-74667D01*
X211400Y-74933D01*
X210800Y-75467D01*
X210400Y-76267D01*
X210200Y-77333D01*
X210400Y-78400D01*
X210800Y-79200D01*
X211400Y-79733D01*
X212100Y-80000D01*
X212800Y-79867D01*
X213400Y-79467D01*
X213800Y-78934D01*
G01X217900Y-82400D02*
X218500Y-82667D01*
X219300Y-82400D01*
X219800Y-81867D01*
X220200Y-81200D01*
X220800Y-79067D01*
X222100Y-74667D01*
G01X218900D02*
X220800Y-79067D01*
G01X226500Y-76400D02*
X229700D01*
X229400Y-75467D01*
X228900Y-74933D01*
X228200Y-74667D01*
X227500Y-74800D01*
X226900Y-75200D01*
X226500Y-76133D01*
X226300Y-76934D01*
Y-77733D01*
X226500Y-78533D01*
X227000Y-79333D01*
X227600Y-79867D01*
X228300Y-80000D01*
X229000Y-79733D01*
X229700Y-78934D01*
G01X234600Y-80000D02*
Y-74667D01*
G01Y-75733D02*
X235100Y-75200D01*
X235600Y-74800D01*
X236300Y-74667D01*
X236800Y-74800D01*
X237400Y-75200D01*
G01X225500Y-122000D02*
Y-130000D01*
G01X223200Y-122000D02*
X227800D01*
G01X233500Y-124667D02*
Y-130000D01*
G01Y-122533D02*
X233300Y-122400D01*
Y-122133D01*
X233500Y-122000D01*
X233700Y-122133D01*
Y-122400D01*
X233500Y-122533D01*
G01X239800Y-130000D02*
Y-124667D01*
G01Y-126000D02*
X240200Y-125333D01*
X240800Y-124800D01*
X241600Y-124667D01*
X242300Y-124800D01*
X242900Y-125333D01*
X243200Y-126267D01*
Y-130000D01*
G01X251300D02*
Y-124667D01*
G01Y-125600D02*
X250900Y-125067D01*
X250300Y-124800D01*
X249600Y-124667D01*
X248900Y-124933D01*
X248300Y-125467D01*
X247900Y-126267D01*
X247700Y-127333D01*
X247900Y-128400D01*
X248300Y-129200D01*
X248900Y-129733D01*
X249600Y-130000D01*
X250300Y-129867D01*
X250900Y-129467D01*
X251300Y-128934D01*
G01X328600Y-123333D02*
X329200Y-122533D01*
X329900Y-122133D01*
X330700Y-122000D01*
X331700Y-122267D01*
X332400Y-122933D01*
X332600Y-123733D01*
X332500Y-124534D01*
X332100Y-125200D01*
X330100Y-126533D01*
X329200Y-127467D01*
X328600Y-128800D01*
X328400Y-130000D01*
X332600D01*
G01X338500Y-122000D02*
X337700Y-122267D01*
X337100Y-122933D01*
X336700Y-123733D01*
X336400Y-124800D01*
X336300Y-126000D01*
X336400Y-127200D01*
X336700Y-128267D01*
X337100Y-129067D01*
X337700Y-129733D01*
X338500Y-130000D01*
X339300Y-129733D01*
X339900Y-129067D01*
X340300Y-128267D01*
X340600Y-127200D01*
X340700Y-126000D01*
X340600Y-124800D01*
X340300Y-123733D01*
X339900Y-122933D01*
X339300Y-122267D01*
X338500Y-122000D01*
G01X346500Y-130000D02*
Y-122000D01*
X345300Y-123600D01*
G01Y-130000D02*
X347700D01*
G01X352300Y-128400D02*
X352900Y-129333D01*
X353700Y-129867D01*
X354600Y-130000D01*
X355400Y-129867D01*
X356200Y-129200D01*
X356700Y-128400D01*
X356800Y-127600D01*
X356600Y-126667D01*
X355900Y-126000D01*
X355200Y-125733D01*
X354300D01*
G01X355200D02*
X355800Y-125333D01*
X356300Y-124667D01*
X356500Y-123867D01*
X356300Y-123067D01*
X355800Y-122400D01*
X354900Y-122000D01*
X354000Y-122133D01*
X353100Y-122667D01*
G01X360700Y-130267D02*
X364300Y-122000D01*
G01X370500D02*
X369700Y-122267D01*
X369100Y-122933D01*
X368700Y-123733D01*
X368400Y-124800D01*
X368300Y-126000D01*
X368400Y-127200D01*
X368700Y-128267D01*
X369100Y-129067D01*
X369700Y-129733D01*
X370500Y-130000D01*
X371300Y-129733D01*
X371900Y-129067D01*
X372300Y-128267D01*
X372600Y-127200D01*
X372700Y-126000D01*
X372600Y-124800D01*
X372300Y-123733D01*
X371900Y-122933D01*
X371300Y-122267D01*
X370500Y-122000D01*
G01X378500Y-130000D02*
Y-122000D01*
X377300Y-123600D01*
G01Y-130000D02*
X379700D01*
G01X384700Y-130267D02*
X388300Y-122000D01*
G01X394500D02*
X393700Y-122267D01*
X393100Y-122933D01*
X392700Y-123733D01*
X392400Y-124800D01*
X392300Y-126000D01*
X392400Y-127200D01*
X392700Y-128267D01*
X393100Y-129067D01*
X393700Y-129733D01*
X394500Y-130000D01*
X395300Y-129733D01*
X395900Y-129067D01*
X396300Y-128267D01*
X396600Y-127200D01*
X396700Y-126000D01*
X396600Y-124800D01*
X396300Y-123733D01*
X395900Y-122933D01*
X395300Y-122267D01*
X394500Y-122000D01*
G01X400800Y-129067D02*
X401500Y-129733D01*
X402300Y-130000D01*
X403100Y-129733D01*
X403800Y-128934D01*
X404300Y-127733D01*
X404500Y-126533D01*
Y-125067D01*
X404300Y-123867D01*
X403800Y-122800D01*
X403200Y-122267D01*
X402500Y-122000D01*
X401700Y-122267D01*
X401100Y-122800D01*
X400700Y-123600D01*
X400500Y-124667D01*
X400700Y-125600D01*
X401200Y-126533D01*
X401800Y-127067D01*
X402500Y-127200D01*
X403300Y-126934D01*
X403900Y-126267D01*
X404500Y-125067D01*
G01X328300Y-105000D02*
Y-97000D01*
X330300D01*
X331100Y-97400D01*
X331700Y-97933D01*
X332200Y-98733D01*
X332600Y-99667D01*
X332700Y-101000D01*
X332600Y-102333D01*
X332200Y-103267D01*
X331700Y-104067D01*
X331100Y-104600D01*
X330300Y-105000D01*
X328300D01*
G01X336000D02*
X338500Y-97000D01*
X341000Y-105000D01*
G01X340100Y-102200D02*
X336900D01*
G01X346500Y-97000D02*
Y-105000D01*
G01X344200Y-97000D02*
X348800D01*
G01X352600Y-101667D02*
X353300Y-100733D01*
X353900Y-100200D01*
X354700Y-99933D01*
X355400Y-100200D01*
X355900Y-100733D01*
X356300Y-101533D01*
X356400Y-102467D01*
X356300Y-103267D01*
X355900Y-104067D01*
X355300Y-104733D01*
X354600Y-105000D01*
X353800Y-104733D01*
X353100Y-103934D01*
X352700Y-102733D01*
X352600Y-101400D01*
X352800Y-99667D01*
X353100Y-98733D01*
X353600Y-97800D01*
X354300Y-97133D01*
X355000Y-97000D01*
X355700Y-97267D01*
X356200Y-97933D01*
G01X359900Y-105000D02*
Y-97000D01*
X362500Y-103667D01*
X365100Y-97000D01*
Y-105000D01*
G01X370500Y-97000D02*
Y-105000D01*
G01X368200Y-97000D02*
X372800D01*
G01X379300Y-100733D02*
X379700Y-100333D01*
X380000Y-99667D01*
X380200Y-98733D01*
X380000Y-97933D01*
X379600Y-97400D01*
X378900Y-97000D01*
X376200D01*
Y-105000D01*
X379500D01*
X380200Y-104467D01*
X380600Y-103667D01*
X380800Y-102733D01*
X380600Y-101800D01*
X380000Y-101000D01*
X379300Y-100733D01*
X376200D01*
G01X386500Y-105000D02*
X387200Y-104867D01*
X388000Y-104467D01*
X388500Y-103800D01*
X388700Y-102867D01*
X388500Y-101934D01*
X387900Y-101133D01*
X387000Y-100733D01*
X386000D01*
X385400Y-100467D01*
X384900Y-99800D01*
X384700Y-98867D01*
X385000Y-97933D01*
X385700Y-97267D01*
X386500Y-97000D01*
X387300Y-97267D01*
X388000Y-97933D01*
X388300Y-98867D01*
X388100Y-99800D01*
X387600Y-100467D01*
X387000Y-100733D01*
X386000D01*
X385100Y-101133D01*
X384500Y-101934D01*
X384300Y-102867D01*
X384500Y-103800D01*
X385000Y-104467D01*
X385800Y-104867D01*
X386500Y-105000D01*
G01X394500D02*
X395200Y-104867D01*
X396000Y-104467D01*
X396500Y-103800D01*
X396700Y-102867D01*
X396500Y-101934D01*
X395900Y-101133D01*
X395000Y-100733D01*
X394000D01*
X393400Y-100467D01*
X392900Y-99800D01*
X392700Y-98867D01*
X393000Y-97933D01*
X393700Y-97267D01*
X394500Y-97000D01*
X395300Y-97267D01*
X396000Y-97933D01*
X396300Y-98867D01*
X396100Y-99800D01*
X395600Y-100467D01*
X395000Y-100733D01*
X394000D01*
X393100Y-101133D01*
X392500Y-101934D01*
X392300Y-102867D01*
X392500Y-103800D01*
X393000Y-104467D01*
X393800Y-104867D01*
X394500Y-105000D01*
G01X400000D02*
X402500Y-97000D01*
X405000Y-105000D01*
G01X404100Y-102200D02*
X400900D01*
G01X410500Y-97000D02*
X409700Y-97267D01*
X409100Y-97933D01*
X408700Y-98733D01*
X408400Y-99800D01*
X408300Y-101000D01*
X408400Y-102200D01*
X408700Y-103267D01*
X409100Y-104067D01*
X409700Y-104733D01*
X410500Y-105000D01*
X411300Y-104733D01*
X411900Y-104067D01*
X412300Y-103267D01*
X412600Y-102200D01*
X412700Y-101000D01*
X412600Y-99800D01*
X412300Y-98733D01*
X411900Y-97933D01*
X411300Y-97267D01*
X410500Y-97000D01*
G01X350500Y-72000D02*
Y-80000D01*
G01X348200Y-72000D02*
X352800D01*
G01X356600Y-76667D02*
X357300Y-75733D01*
X357900Y-75200D01*
X358700Y-74933D01*
X359400Y-75200D01*
X359900Y-75733D01*
X360300Y-76533D01*
X360400Y-77467D01*
X360300Y-78267D01*
X359900Y-79067D01*
X359300Y-79733D01*
X358600Y-80000D01*
X357800Y-79733D01*
X357100Y-78934D01*
X356700Y-77733D01*
X356600Y-76400D01*
X356800Y-74667D01*
X357100Y-73733D01*
X357600Y-72800D01*
X358300Y-72133D01*
X359000Y-72000D01*
X359700Y-72267D01*
X360200Y-72933D01*
G01X363900Y-80000D02*
Y-72000D01*
X366500Y-78667D01*
X369100Y-72000D01*
Y-80000D01*
G01X375100Y-76000D02*
X377100D01*
Y-78400D01*
X376500Y-79200D01*
X375800Y-79733D01*
X374800Y-80000D01*
X373800Y-79733D01*
X373100Y-79200D01*
X372500Y-78400D01*
X372100Y-77467D01*
X371900Y-76400D01*
Y-75467D01*
X372100Y-74667D01*
X372500Y-73733D01*
X373100Y-72933D01*
X373700Y-72400D01*
X374500Y-72000D01*
X375200D01*
X376000Y-72267D01*
X376600Y-72800D01*
G01X379500Y-82667D02*
X385500D01*
G01X388500Y-80000D02*
Y-72000D01*
X390900D01*
X391700Y-72400D01*
X392300Y-73333D01*
X392500Y-74400D01*
X392300Y-75467D01*
X391800Y-76267D01*
X390900Y-76667D01*
X388500D01*
G01X396300Y-80000D02*
Y-72000D01*
X398300D01*
X399100Y-72400D01*
X399700Y-72933D01*
X400200Y-73733D01*
X400600Y-74667D01*
X400700Y-76000D01*
X400600Y-77333D01*
X400200Y-78267D01*
X399700Y-79067D01*
X399100Y-79600D01*
X398300Y-80000D01*
X396300D01*
G01X407300Y-75733D02*
X407700Y-75333D01*
X408000Y-74667D01*
X408200Y-73733D01*
X408000Y-72933D01*
X407600Y-72400D01*
X406900Y-72000D01*
X404200D01*
Y-80000D01*
X407500D01*
X408200Y-79467D01*
X408600Y-78667D01*
X408800Y-77733D01*
X408600Y-76800D01*
X408000Y-76000D01*
X407300Y-75733D01*
X404200D01*
G01X411500Y-82667D02*
X417500D01*
G01X420000Y-80000D02*
X422500Y-72000D01*
X425000Y-80000D01*
G01X424100Y-77200D02*
X420900D01*
G01X427500Y-82667D02*
X433500D01*
G01X439300Y-75733D02*
X439700Y-75333D01*
X440000Y-74667D01*
X440200Y-73733D01*
X440000Y-72933D01*
X439600Y-72400D01*
X438900Y-72000D01*
X436200D01*
Y-80000D01*
X439500D01*
X440200Y-79467D01*
X440600Y-78667D01*
X440800Y-77733D01*
X440600Y-76800D01*
X440000Y-76000D01*
X439300Y-75733D01*
X436200D01*
G01X444300Y-80000D02*
Y-72000D01*
X446300D01*
X447100Y-72400D01*
X447700Y-72933D01*
X448200Y-73733D01*
X448600Y-74667D01*
X448700Y-76000D01*
X448600Y-77333D01*
X448200Y-78267D01*
X447700Y-79067D01*
X447100Y-79600D01*
X446300Y-80000D01*
X444300D01*
G01X443000Y-130000D02*
X445500Y-122000D01*
X448000Y-130000D01*
G01X447100Y-127200D02*
X443900D01*
G01X473000Y-130000D02*
Y-122000D01*
X471800Y-123600D01*
G01Y-130000D02*
X474200D01*
G01X479100Y-126667D02*
X479800Y-125733D01*
X480400Y-125200D01*
X481200Y-124933D01*
X481900Y-125200D01*
X482400Y-125733D01*
X482800Y-126533D01*
X482900Y-127467D01*
X482800Y-128267D01*
X482400Y-129067D01*
X481800Y-129733D01*
X481100Y-130000D01*
X480300Y-129733D01*
X479600Y-128934D01*
X479200Y-127733D01*
X479100Y-126400D01*
X479300Y-124667D01*
X479600Y-123733D01*
X480100Y-122800D01*
X480800Y-122133D01*
X481500Y-122000D01*
X482200Y-122267D01*
X482700Y-122933D01*
G54D18*
X54979Y70500D03*
Y206500D03*
Y279500D03*
Y415500D03*
X203542Y73105D03*
X204069Y152050D03*
X204137Y247568D03*
X204597Y331786D03*
X203541Y421732D03*
X204333Y506517D03*
X206668Y598130D03*
X204596Y681645D03*
X205626Y774526D03*
X205386Y856244D03*
X210091Y947202D03*
X209296Y1032544D03*
X205030Y1122856D03*
X205122Y1206233D03*
X205626Y1299104D03*
X204332Y1380966D03*
X203243Y1474162D03*
X204859Y1557277D03*
X205923Y1648177D03*
X205387Y1731351D03*
X205310Y1823227D03*
X204069Y1900420D03*
X205905Y1998730D03*
X205310Y2043388D03*
G54D19*
X65354Y101180D03*
X55511Y105117D03*
X51574Y114960D03*
X55511Y124803D03*
X65354Y128740D03*
Y451180D03*
X55511Y455117D03*
X51574Y464960D03*
X55511Y474803D03*
X65354Y478740D03*
Y801180D03*
X55511Y805117D03*
X51574Y814960D03*
X55511Y824803D03*
X65354Y828740D03*
Y1151180D03*
X55511Y1155117D03*
X51574Y1164960D03*
X55511Y1174803D03*
X65354Y1178740D03*
Y1501180D03*
X55511Y1505117D03*
X51574Y1514960D03*
X55511Y1524803D03*
X65354Y1528740D03*
Y1851180D03*
X55511Y1855117D03*
X51574Y1864960D03*
X55511Y1874803D03*
X65354Y1878740D03*
X75197Y105117D03*
Y124803D03*
X79134Y114960D03*
Y464960D03*
X75197Y455117D03*
Y474803D03*
Y805117D03*
Y824803D03*
X79134Y814960D03*
Y1164960D03*
X75197Y1155117D03*
Y1174803D03*
Y1505117D03*
Y1524803D03*
X79134Y1514960D03*
Y1864960D03*
X75197Y1855117D03*
Y1874803D03*
X307086Y113385D03*
X297243Y117322D03*
X293306Y127165D03*
X297243Y137008D03*
X307086Y140945D03*
Y463385D03*
X297243Y467322D03*
X293306Y477165D03*
X297243Y487008D03*
X307086Y490945D03*
Y813385D03*
X297243Y817322D03*
X293306Y827165D03*
X297243Y837008D03*
X307086Y840945D03*
Y1329724D03*
X297243Y1333661D03*
X293306Y1343504D03*
X297243Y1353347D03*
X307086Y1357284D03*
Y1679724D03*
X297243Y1683661D03*
X293306Y1693504D03*
X297243Y1703347D03*
X307086Y1707284D03*
X307087Y2029723D03*
X297244Y2033660D03*
X293307Y2043503D03*
X297244Y2053346D03*
X307087Y2057283D03*
X320866Y127165D03*
X316929Y117322D03*
Y137008D03*
Y467322D03*
Y487008D03*
X320866Y477165D03*
Y827165D03*
X316929Y817322D03*
Y837008D03*
Y1333661D03*
Y1353347D03*
X320866Y1343504D03*
Y1693504D03*
X316929Y1683661D03*
Y1703347D03*
X316930Y2033660D03*
Y2053346D03*
X320867Y2043503D03*
M02*
